# BASEBOARD_FAB2 (Tioga Pass) — schematic netlist excerpt (pin names and nets, part order shuffled) for the footprints in the layout excerpt that follows; sources: Cadence DE-HDL packaged netlist, KiCad conversion of Wiwynn_Tioga_Pass_MB.brd

T1D10  TEST-PAD-12P-1-GP-U  pkg DISCRET-GB1  page 257
  DP  = L12_85OHM_5INCH_DN
  DN  = L12_85OHM_5INCH_DP
  GND(0)  = GND
  GND(1)  = GND
  GND(2)  = GND
  GND(3)  = GND
  GND(4)  = GND
  GND(5)  = GND
  GND(6)  = GND
  GND(7)  = GND
  GND(8)  = GND
  GND(9)  = GND

R7A12  RES  0.0 5% CHIP  pkg 0402  page 218 : A = SVID_VDIO_PVDDQ_DEF ; B = SVID_DIO1_CPU0_R

(kicad_pcb
	(version 20260206)
	(generator "pcbnew")
	(generator_version "10.0")
	(general
		(thickness 1.6)
		(legacy_teardrops no)
	)
	(paper "A4")
	(title_block
		(title "Wiwynn_Tioga_Pass_MB.brd")
		(comment 1 "Tioga Pass / footprints 568-569 of 4770")
	)
	(layers
		(0 "F.Cu" signal "TOP")
		(4 "In1.Cu" signal "L2GND")
		(6 "In2.Cu" signal "L3")
		(8 "In3.Cu" signal "L4GND")
		(10 "In4.Cu" signal "L5")
		(12 "In5.Cu" signal "L6GND")
		(14 "In6.Cu" signal "L7VCC")
		(16 "In7.Cu" signal "L8VCC")
		(18 "In8.Cu" signal "L9GND")
		(20 "In9.Cu" signal "L10")
		(22 "In10.Cu" signal "L11GND")
		(24 "In11.Cu" signal "L12")
		(26 "In12.Cu" signal "L13GND")
		(2 "B.Cu" signal "BOTTOM")
		(9 "F.Adhes" user "F.Adhesive")
		(11 "B.Adhes" user "B.Adhesive")
		(13 "F.Paste" user "Package Geometry/Pastemask Top")
		(15 "B.Paste" user "Package Geometry/Pastemask Bottom")
		(5 "F.SilkS" user "Ref Des/Silkscreen Top")
		(7 "B.SilkS" user "Ref Des/Silkscreen Bottom")
		(1 "F.Mask" user "Board Geometry/Soldermask Top")
		(3 "B.Mask" user "Board Geometry/Soldermask Bottom")
		(17 "Dwgs.User" user "User.Drawings")
		(19 "Cmts.User" user "User.Comments")
		(21 "Eco1.User" user "User.Eco1")
		(23 "Eco2.User" user "User.Eco2")
		(25 "Edge.Cuts" user "Board Geometry/Outline")
		(27 "Margin" user)
		(31 "F.CrtYd" user "Package Geometry/Place Bound Top")
		(29 "B.CrtYd" user "Package Geometry/Place Bound Bottom")
		(35 "F.Fab" user "Ref Des/Assembly Top")
		(33 "B.Fab" user "Ref Des/Assembly Bottom")
	)
	(footprint ""
		(layer "F.Cu")
		(at 363.87024 -138.41857 90)
		(property "Reference" "R7A12"
			(at 0 0 90)
			(layer "F.SilkS")
			(hide yes)
			(effects
				(font
					(size 1.27 1.27)
				)
			)
		)
		(property "Value" ""
			(at 0 0 90)
			(layer "F.Fab")
			(effects
				(font
					(size 1.27 1.27)
				)
			)
		)
		(duplicate_pad_numbers_are_jumpers no)
		(fp_rect
			(start -0.2794 -0.1016)
			(end 0.2794 0.9906)
			(stroke
				(width 0)
				(type default)
			)
			(fill no)
			(layer "F.CrtYd")
		)
		(fp_line
			(start 0.2794 -0.1016)
			(end -0.2794 -0.1016)
			(stroke
				(width 0.1)
				(type default)
			)
			(layer "F.Fab")
		)
		(fp_line
			(start -0.2794 -0.1016)
			(end -0.2794 0.9906)
			(stroke
				(width 0.1)
				(type default)
			)
			(layer "F.Fab")
		)
		(fp_line
			(start 0.2794 0.9906)
			(end 0.2794 -0.1016)
			(stroke
				(width 0.1)
				(type default)
			)
			(layer "F.Fab")
		)
		(fp_line
			(start -0.2794 0.9906)
			(end 0.2794 0.9906)
			(stroke
				(width 0.1)
				(type default)
			)
			(layer "F.Fab")
		)
		(pad "1" smd rect
			(at 0 0 90)
			(size 0.508 0.508)
			(layers "F.Cu" "F.Mask" "F.Paste")
			(net "SVID_VDIO_PVDDQ_DEF")
		)
		(pad "2" smd rect
			(at 0 0.889 90)
			(size 0.508 0.508)
			(layers "F.Cu" "F.Mask" "F.Paste")
			(net "SVID_DIO1_CPU0_R")
		)
		(zone
			(layer "F.Cu")
			(hatch none 0.5)
			(connect_pads
				(clearance 0)
			)
			(min_thickness 0.25)
			(keepout
				(tracks allowed)
				(vias not_allowed)
				(pads allowed)
				(copperpour not_allowed)
				(footprints allowed)
			)
			(placement
				(enabled no)
				(sheetname "")
			)
			(fill
				(thermal_gap 0.5)
				(thermal_bridge_width 0.5)
				(island_removal_mode 0)
			)
			(polygon
				(pts
					(xy 364.12424 -138.16457) (xy 364.50524 -138.16457) (xy 364.50524 -138.67257) (xy 364.12424 -138.67257)
				)
			)
		)
		(zone
			(layer "F.Cu")
			(hatch none 0.5)
			(connect_pads
				(clearance 0)
			)
			(min_thickness 0.25)
			(keepout
				(tracks not_allowed)
				(vias allowed)
				(pads allowed)
				(copperpour not_allowed)
				(footprints allowed)
			)
			(placement
				(enabled no)
				(sheetname "")
			)
			(fill
				(thermal_gap 0.5)
				(thermal_bridge_width 0.5)
				(island_removal_mode 0)
			)
			(polygon
				(pts
					(xy 364.12424 -138.16457) (xy 364.50524 -138.16457) (xy 364.50524 -138.67257) (xy 364.12424 -138.67257)
				)
			)
		)
	)
	(footprint ""
		(layer "F.Cu")
		(at 61.285628 -165.04158 -90)
		(property "Reference" "T1D10"
			(at 0 0 270)
			(layer "F.SilkS")
			(hide yes)
			(effects
				(font
					(size 1.27 1.27)
				)
			)
		)
		(property "Value" "*"
			(at -3.4036 -4.46405 270)
			(unlocked yes)
			(layer "F.Fab")
			(hide yes)
			(effects
				(font
					(size 0.889 0.889)
					(thickness 0.1524)
				)
			)
		)
		(property "Device Type" "TEST-PAD-12P-1-GP-U_DISCRET-GBA"
			(at -3.4036 -5.98805 270)
			(unlocked yes)
			(layer "F.Fab")
			(hide yes)
			(effects
				(font
					(size 0.889 0.889)
					(thickness 0.1524)
				)
			)
		)
		(duplicate_pad_numbers_are_jumpers no)
		(fp_line
			(start -2.3876 3.4798)
			(end -2.3876 -4.826)
			(stroke
				(width 0.1524)
				(type default)
			)
			(layer "F.SilkS")
		)
		(fp_line
			(start 2.3622 3.4798)
			(end -2.3876 3.4798)
			(stroke
				(width 0.1524)
				(type default)
			)
			(layer "F.SilkS")
		)
		(fp_line
			(start -2.3876 -4.826)
			(end 2.3622 -4.826)
			(stroke
				(width 0.1524)
				(type default)
			)
			(layer "F.SilkS")
		)
		(fp_line
			(start 2.3622 -4.826)
			(end 2.3622 3.4798)
			(stroke
				(width 0.1524)
				(type default)
			)
			(layer "F.SilkS")
		)
		(fp_rect
			(start -2.6416 3.7338)
			(end 2.6162 -5.08)
			(stroke
				(width 0)
				(type default)
			)
			(fill no)
			(layer "F.CrtYd")
		)
		(fp_rect
			(start -2.6416 3.7338)
			(end 2.6162 -5.08)
			(stroke
				(width 0)
				(type default)
			)
			(fill no)
			(layer "F.Fab")
		)
		(pad "1" smd circle
			(at 0.496824 -1.301496 270)
			(size 0.6604 0.6604)
			(layers "F.Cu" "F.Mask" "F.Paste")
			(net "L12_85OHM_5INCH_DN")
		)
		(pad "2" smd circle
			(at -0.503936 -1.301496 270)
			(size 0.6604 0.6604)
			(layers "F.Cu" "F.Mask" "F.Paste")
			(net "L12_85OHM_5INCH_DP")
		)
		(pad "3" smd custom
			(at -0.00889 0.370078 270)
			(size 0.74295 0.74295)
			(layers "F.Cu" "F.Mask" "F.Paste")
			(net "GND")
			(options
				(clearance outline)
				(anchor circle)
			)
			(primitives
				(gr_poly
					(pts
						(xy -2.1209 1.4859) (xy 2.1209 1.4859) (xy 2.1209 -1.4859) (xy 1.08585 -1.4859) (xy 1.08585 -0.4699)
						(xy -1.08585 -0.4699) (xy -1.08585 -1.4859) (xy -2.1209 -1.4859)
					)
					(width 0)
					(fill yes)
				)
			)
		)
		(pad "4" thru_hole circle
			(at 1.266444 -3.851656 270)
			(size 1.4478 1.4478)
			(drill 1.0414)
			(layers "*.Cu" "*.Mask")
			(remove_unused_layers no)
			(net "GND")
			(clearance 0.1524)
			(thermal_gap 0.1524)
		)
		(pad "5" thru_hole circle
			(at -1.273556 -3.851656 270)
			(size 1.4478 1.4478)
			(drill 1.0414)
			(layers "*.Cu" "*.Mask")
			(remove_unused_layers no)
			(net "GND")
			(clearance 0.1524)
			(thermal_gap 0.1524)
		)
		(pad "6" thru_hole circle
			(at 1.266444 2.498344 270)
			(size 1.4478 1.4478)
			(drill 1.0414)
			(layers "*.Cu" "*.Mask")
			(remove_unused_layers no)
			(net "GND")
			(clearance 0.1524)
			(thermal_gap 0.1524)
		)
		(pad "7" thru_hole circle
			(at -1.273556 2.498344 270)
			(size 1.4478 1.4478)
			(drill 1.0414)
			(layers "*.Cu" "*.Mask")
			(remove_unused_layers no)
			(net "GND")
			(clearance 0.1524)
			(thermal_gap 0.1524)
		)
		(pad "8" thru_hole circle
			(at 1.27 -0.4572 270)
			(size 0.7112 0.7112)
			(drill 0.4064)
			(layers "*.Cu" "*.Mask")
			(remove_unused_layers no)
			(net "GND")
			(clearance 0.1016)
			(thermal_gap 0.1016)
		)
		(pad "9" thru_hole circle
			(at 1.27 0.762 270)
			(size 0.7112 0.7112)
			(drill 0.4064)
			(layers "*.Cu" "*.Mask")
			(remove_unused_layers no)
			(net "GND")
			(clearance 0.1016)
			(thermal_gap 0.1016)
		)
		(pad "10" thru_hole circle
			(at -0.0254 0.762 270)
			(size 0.7112 0.7112)
			(drill 0.4064)
			(layers "*.Cu" "*.Mask")
			(remove_unused_layers no)
			(net "GND")
			(clearance 0.1016)
			(thermal_gap 0.1016)
		)
		(pad "11" thru_hole circle
			(at -1.27 0.762 270)
			(size 0.7112 0.7112)
			(drill 0.4064)
			(layers "*.Cu" "*.Mask")
			(remove_unused_layers no)
			(net "GND")
			(clearance 0.1016)
			(thermal_gap 0.1016)
		)
		(pad "12" thru_hole circle
			(at -1.27 -0.4572 270)
			(size 0.7112 0.7112)
			(drill 0.4064)
			(layers "*.Cu" "*.Mask")
			(remove_unused_layers no)
			(net "GND")
			(clearance 0.1016)
			(thermal_gap 0.1016)
		)
	)
)
